(kicad_pcb
	(version 20260206)
	(generator "pcbnew")
	(generator_version "10.0")
	(general
		(thickness 1.6)
		(legacy_teardrops no)
	)
	(paper "A4")
	(title_block
		(title "01162023_DA0F0TEBIF0_F0T_Expander_BD_F_brd_V02_OCP.brd")
		(comment 1 "Grand Teton / footprints 6679-6685 of 9728")
	)
	(layers
		(0 "F.Cu" signal "TOP")
		(4 "In1.Cu" signal "GND")
		(6 "In2.Cu" signal "VCC")
		(8 "In3.Cu" signal "VCC1")
		(10 "In4.Cu" signal "GND1")
		(12 "In5.Cu" signal "IN1")
		(14 "In6.Cu" signal "GND2")
		(16 "In7.Cu" signal "IN2")
		(18 "In8.Cu" signal "GND3")
		(20 "In9.Cu" signal "IN3")
		(22 "In10.Cu" signal "GND4")
		(24 "In11.Cu" signal "IN4")
		(26 "In12.Cu" signal "GND5")
		(28 "In13.Cu" signal "IN5")
		(30 "In14.Cu" signal "GND6")
		(32 "In15.Cu" signal "IN6")
		(34 "In16.Cu" signal "GND7")
		(2 "B.Cu" signal "BOTTOM")
		(9 "F.Adhes" user "F.Adhesive")
		(11 "B.Adhes" user "B.Adhesive")
		(13 "F.Paste" user "Package Geometry/Pastemask Top")
		(15 "B.Paste" user "Package Geometry/Pastemask Bottom")
		(5 "F.SilkS" user "Ref Des/Silkscreen Top")
		(7 "B.SilkS" user "Ref Des/Silkscreen Bottom")
		(1 "F.Mask" user "Board Geometry/Soldermask Top")
		(3 "B.Mask" user "Board Geometry/Soldermask Bottom")
		(17 "Dwgs.User" user "User.Drawings")
		(19 "Cmts.User" user "User.Comments")
		(21 "Eco1.User" user "User.Eco1")
		(23 "Eco2.User" user "User.Eco2")
		(25 "Edge.Cuts" user "Board Geometry/Outline")
		(27 "Margin" user)
		(31 "F.CrtYd" user "Package Geometry/Place Bound Top")
		(29 "B.CrtYd" user "Package Geometry/Place Bound Bottom")
		(35 "F.Fab" user "Ref Des/Assembly Top")
		(33 "B.Fab" user "Ref Des/Assembly Bottom")
	)
	(footprint ""
		(layer "F.Cu")
		(at 223.50476 -314.068714 180)
		(property "Reference" "PC228"
			(at 0 0 180)
			(layer "F.SilkS")
			(hide yes)
			(effects
				(font
					(size 1.27 1.27)
				)
			)
		)
		(property "Value" ""
			(at 0 0 180)
			(layer "F.Fab")
			(effects
				(font
					(size 1.27 1.27)
				)
			)
		)
		(duplicate_pad_numbers_are_jumpers no)
		(fp_line
			(start 1.524 0.762)
			(end -1.524 0.762)
			(stroke
				(width 0.1524)
				(type default)
			)
			(layer "F.SilkS")
		)
		(fp_line
			(start 1.524 -0.762)
			(end 1.524 0.762)
			(stroke
				(width 0.1524)
				(type default)
			)
			(layer "F.SilkS")
		)
		(fp_line
			(start -1.524 0.762)
			(end -1.524 -0.762)
			(stroke
				(width 0.1524)
				(type default)
			)
			(layer "F.SilkS")
		)
		(fp_line
			(start -1.524 -0.762)
			(end 1.524 -0.762)
			(stroke
				(width 0.1524)
				(type default)
			)
			(layer "F.SilkS")
		)
		(fp_line
			(start 1.1049 0.724916)
			(end 1.1049 -0.724916)
			(stroke
				(width 0.1)
				(type default)
			)
			(layer "F.Fab")
		)
		(fp_line
			(start 1.1049 -0.724916)
			(end -1.1049 -0.724916)
			(stroke
				(width 0.1)
				(type default)
			)
			(layer "F.Fab")
		)
		(fp_line
			(start -1.1049 0.724916)
			(end 1.1049 0.724916)
			(stroke
				(width 0.1)
				(type default)
			)
			(layer "F.Fab")
		)
		(fp_line
			(start -1.1049 -0.724916)
			(end -1.1049 0.724916)
			(stroke
				(width 0.1)
				(type default)
			)
			(layer "F.Fab")
		)
		(pad "1" smd rect
			(at -0.889 0)
			(size 1.016 1.27)
			(layers "F.Cu" "F.Mask" "F.Paste")
			(net "SW_P12V_P1V25_PEX1_FLT")
		)
		(pad "2" smd rect
			(at 0.889 0)
			(size 1.016 1.27)
			(layers "F.Cu" "F.Mask" "F.Paste")
			(net "GND")
		)
	)
	(footprint ""
		(layer "F.Cu")
		(at 361.188 -184.15 180)
		(property "Reference" "R4648"
			(at 0 0 180)
			(layer "F.SilkS")
			(hide yes)
			(effects
				(font
					(size 1.27 1.27)
				)
			)
		)
		(property "Value" ""
			(at 0 0 180)
			(layer "F.Fab")
			(effects
				(font
					(size 1.27 1.27)
				)
			)
		)
		(duplicate_pad_numbers_are_jumpers no)
		(fp_line
			(start 0.7874 0.4064)
			(end -0.7874 0.4064)
			(stroke
				(width 0.1524)
				(type default)
			)
			(layer "F.SilkS")
		)
		(fp_line
			(start 0.7874 -0.4064)
			(end 0.7874 0.4064)
			(stroke
				(width 0.1524)
				(type default)
			)
			(layer "F.SilkS")
		)
		(fp_line
			(start -0.7874 0.4064)
			(end -0.7874 -0.4064)
			(stroke
				(width 0.1524)
				(type default)
			)
			(layer "F.SilkS")
		)
		(fp_line
			(start -0.7874 -0.4064)
			(end 0.7874 -0.4064)
			(stroke
				(width 0.1524)
				(type default)
			)
			(layer "F.SilkS")
		)
		(fp_line
			(start 0.67945 0.3048)
			(end 0.120396 0.3048)
			(stroke
				(width 0.1)
				(type default)
			)
			(layer "F.Fab")
		)
		(fp_line
			(start 0.67945 -0.3048)
			(end 0.67945 0.3048)
			(stroke
				(width 0.1)
				(type default)
			)
			(layer "F.Fab")
		)
		(fp_line
			(start 0.12065 -0.2794)
			(end 0.12065 -0.3048)
			(stroke
				(width 0.1)
				(type default)
			)
			(layer "F.Fab")
		)
		(fp_line
			(start 0.12065 -0.3048)
			(end 0.67945 -0.3048)
			(stroke
				(width 0.1)
				(type default)
			)
			(layer "F.Fab")
		)
		(fp_line
			(start 0.120396 0.3048)
			(end 0.120396 0.2794)
			(stroke
				(width 0.1)
				(type default)
			)
			(layer "F.Fab")
		)
		(fp_line
			(start 0.120396 0.2794)
			(end -0.12065 0.2794)
			(stroke
				(width 0.1)
				(type default)
			)
			(layer "F.Fab")
		)
		(fp_line
			(start -0.12065 0.3048)
			(end -0.67945 0.3048)
			(stroke
				(width 0.1)
				(type default)
			)
			(layer "F.Fab")
		)
		(fp_line
			(start -0.12065 0.2794)
			(end -0.12065 0.3048)
			(stroke
				(width 0.1)
				(type default)
			)
			(layer "F.Fab")
		)
		(fp_line
			(start -0.12065 -0.2794)
			(end 0.12065 -0.2794)
			(stroke
				(width 0.1)
				(type default)
			)
			(layer "F.Fab")
		)
		(fp_line
			(start -0.12065 -0.305054)
			(end -0.12065 -0.2794)
			(stroke
				(width 0.1)
				(type default)
			)
			(layer "F.Fab")
		)
		(fp_line
			(start -0.67945 0.3048)
			(end -0.67945 -0.305054)
			(stroke
				(width 0.1)
				(type default)
			)
			(layer "F.Fab")
		)
		(fp_line
			(start -0.67945 -0.305054)
			(end -0.12065 -0.305054)
			(stroke
				(width 0.1)
				(type default)
			)
			(layer "F.Fab")
		)
		(pad "1" smd circle
			(at -0.40005 0 180)
			(size 0 0)
			(layers "F.Cu" "F.Mask" "F.Paste")
			(net "RST_PEX_SSD3_PERST_N")
		)
		(pad "2" smd circle
			(at 0.40005 0 180)
			(size 0 0)
			(layers "F.Cu" "F.Mask" "F.Paste")
			(net "RST_PEX_SSD3_PERST_R_N")
		)
	)
	(footprint ""
		(layer "F.Cu")
		(at 393.669266 -84.928202 180)
		(property "Reference" "R1774"
			(at 0 0 180)
			(layer "F.SilkS")
			(hide yes)
			(effects
				(font
					(size 1.27 1.27)
				)
			)
		)
		(property "Value" ""
			(at 0 0 180)
			(layer "F.Fab")
			(effects
				(font
					(size 1.27 1.27)
				)
			)
		)
		(duplicate_pad_numbers_are_jumpers no)
		(fp_line
			(start 0.7874 0.4064)
			(end -0.7874 0.4064)
			(stroke
				(width 0.1524)
				(type default)
			)
			(layer "F.SilkS")
		)
		(fp_line
			(start 0.7874 -0.4064)
			(end 0.7874 0.4064)
			(stroke
				(width 0.1524)
				(type default)
			)
			(layer "F.SilkS")
		)
		(fp_line
			(start -0.7874 0.4064)
			(end -0.7874 -0.4064)
			(stroke
				(width 0.1524)
				(type default)
			)
			(layer "F.SilkS")
		)
		(fp_line
			(start -0.7874 -0.4064)
			(end 0.7874 -0.4064)
			(stroke
				(width 0.1524)
				(type default)
			)
			(layer "F.SilkS")
		)
		(fp_line
			(start 0.67945 0.3048)
			(end 0.120396 0.3048)
			(stroke
				(width 0.1)
				(type default)
			)
			(layer "F.Fab")
		)
		(fp_line
			(start 0.67945 -0.3048)
			(end 0.67945 0.3048)
			(stroke
				(width 0.1)
				(type default)
			)
			(layer "F.Fab")
		)
		(fp_line
			(start 0.12065 -0.2794)
			(end 0.12065 -0.3048)
			(stroke
				(width 0.1)
				(type default)
			)
			(layer "F.Fab")
		)
		(fp_line
			(start 0.12065 -0.3048)
			(end 0.67945 -0.3048)
			(stroke
				(width 0.1)
				(type default)
			)
			(layer "F.Fab")
		)
		(fp_line
			(start 0.120396 0.3048)
			(end 0.120396 0.2794)
			(stroke
				(width 0.1)
				(type default)
			)
			(layer "F.Fab")
		)
		(fp_line
			(start 0.120396 0.2794)
			(end -0.12065 0.2794)
			(stroke
				(width 0.1)
				(type default)
			)
			(layer "F.Fab")
		)
		(fp_line
			(start -0.12065 0.3048)
			(end -0.67945 0.3048)
			(stroke
				(width 0.1)
				(type default)
			)
			(layer "F.Fab")
		)
		(fp_line
			(start -0.12065 0.2794)
			(end -0.12065 0.3048)
			(stroke
				(width 0.1)
				(type default)
			)
			(layer "F.Fab")
		)
		(fp_line
			(start -0.12065 -0.2794)
			(end 0.12065 -0.2794)
			(stroke
				(width 0.1)
				(type default)
			)
			(layer "F.Fab")
		)
		(fp_line
			(start -0.12065 -0.305054)
			(end -0.12065 -0.2794)
			(stroke
				(width 0.1)
				(type default)
			)
			(layer "F.Fab")
		)
		(fp_line
			(start -0.67945 0.3048)
			(end -0.67945 -0.305054)
			(stroke
				(width 0.1)
				(type default)
			)
			(layer "F.Fab")
		)
		(fp_line
			(start -0.67945 -0.305054)
			(end -0.12065 -0.305054)
			(stroke
				(width 0.1)
				(type default)
			)
			(layer "F.Fab")
		)
		(pad "1" smd circle
			(at -0.40005 0 180)
			(size 0 0)
			(layers "F.Cu" "F.Mask" "F.Paste")
			(net "SMB_BIC_I2C6_MUX_VR_R_SDA")
		)
		(pad "2" smd circle
			(at 0.40005 0 180)
			(size 0 0)
			(layers "F.Cu" "F.Mask" "F.Paste")
			(net "SMB_BIC_I2C6_MUX_VR_SDA")
		)
	)
	(footprint ""
		(layer "F.Cu")
		(at 387.580632 -133.129782)
		(property "Reference" "C671"
			(at 0 0 0)
			(layer "F.SilkS")
			(hide yes)
			(effects
				(font
					(size 1.27 1.27)
				)
			)
		)
		(property "Value" ""
			(at 0 0 0)
			(layer "F.Fab")
			(effects
				(font
					(size 1.27 1.27)
				)
			)
		)
		(duplicate_pad_numbers_are_jumpers no)
		(fp_line
			(start -0.299974 -0.150114)
			(end 0.299974 -0.150114)
			(stroke
				(width 0.1)
				(type default)
			)
			(layer "F.Fab")
		)
		(fp_line
			(start -0.299974 0.150114)
			(end -0.299974 -0.150114)
			(stroke
				(width 0.1)
				(type default)
			)
			(layer "F.Fab")
		)
		(fp_line
			(start 0.299974 -0.150114)
			(end 0.299974 0.150114)
			(stroke
				(width 0.1)
				(type default)
			)
			(layer "F.Fab")
		)
		(fp_line
			(start 0.299974 0.150114)
			(end -0.299974 0.150114)
			(stroke
				(width 0.1)
				(type default)
			)
			(layer "F.Fab")
		)
		(pad "1" smd rect
			(at -0.2667 0)
			(size 0.3048 0.381)
			(layers "F.Cu" "F.Mask" "F.Paste")
			(net "P5E_PEX3_STN1_TX_DP<29>")
		)
		(pad "2" smd rect
			(at 0.2667 0)
			(size 0.3048 0.381)
			(layers "F.Cu" "F.Mask" "F.Paste")
			(net "P5E_PEX3_STN1_TX_C_DP<29>")
		)
	)
	(footprint ""
		(layer "F.Cu")
		(at 36.312094 -137.2489 -90)
		(property "Reference" "C853"
			(at 0 0 270)
			(layer "F.SilkS")
			(hide yes)
			(effects
				(font
					(size 1.27 1.27)
				)
			)
		)
		(property "Value" ""
			(at 0 0 270)
			(layer "F.Fab")
			(effects
				(font
					(size 1.27 1.27)
				)
			)
		)
		(duplicate_pad_numbers_are_jumpers no)
		(fp_line
			(start -0.7874 0.4064)
			(end -0.7874 -0.4064)
			(stroke
				(width 0.1524)
				(type default)
			)
			(layer "F.SilkS")
		)
		(fp_line
			(start 0.7874 0.4064)
			(end -0.7874 0.4064)
			(stroke
				(width 0.1524)
				(type default)
			)
			(layer "F.SilkS")
		)
		(fp_line
			(start -0.7874 -0.4064)
			(end 0.7874 -0.4064)
			(stroke
				(width 0.1524)
				(type default)
			)
			(layer "F.SilkS")
		)
		(fp_line
			(start 0.7874 -0.4064)
			(end 0.7874 0.4064)
			(stroke
				(width 0.1524)
				(type default)
			)
			(layer "F.SilkS")
		)
		(fp_line
			(start -0.67945 0.3048)
			(end -0.67945 -0.305054)
			(stroke
				(width 0.1)
				(type default)
			)
			(layer "F.Fab")
		)
		(fp_line
			(start -0.12065 0.3048)
			(end -0.67945 0.3048)
			(stroke
				(width 0.1)
				(type default)
			)
			(layer "F.Fab")
		)
		(fp_line
			(start 0.120396 0.3048)
			(end 0.120396 0.2794)
			(stroke
				(width 0.1)
				(type default)
			)
			(layer "F.Fab")
		)
		(fp_line
			(start 0.67945 0.3048)
			(end 0.120396 0.3048)
			(stroke
				(width 0.1)
				(type default)
			)
			(layer "F.Fab")
		)
		(fp_line
			(start -0.12065 0.2794)
			(end -0.12065 0.3048)
			(stroke
				(width 0.1)
				(type default)
			)
			(layer "F.Fab")
		)
		(fp_line
			(start 0.120396 0.2794)
			(end -0.12065 0.2794)
			(stroke
				(width 0.1)
				(type default)
			)
			(layer "F.Fab")
		)
		(fp_line
			(start -0.12065 -0.2794)
			(end 0.12065 -0.2794)
			(stroke
				(width 0.1)
				(type default)
			)
			(layer "F.Fab")
		)
		(fp_line
			(start 0.12065 -0.2794)
			(end 0.12065 -0.3048)
			(stroke
				(width 0.1)
				(type default)
			)
			(layer "F.Fab")
		)
		(fp_line
			(start 0.12065 -0.3048)
			(end 0.67945 -0.3048)
			(stroke
				(width 0.1)
				(type default)
			)
			(layer "F.Fab")
		)
		(fp_line
			(start 0.67945 -0.3048)
			(end 0.67945 0.3048)
			(stroke
				(width 0.1)
				(type default)
			)
			(layer "F.Fab")
		)
		(fp_line
			(start -0.67945 -0.305054)
			(end -0.12065 -0.305054)
			(stroke
				(width 0.1)
				(type default)
			)
			(layer "F.Fab")
		)
		(fp_line
			(start -0.12065 -0.305054)
			(end -0.12065 -0.2794)
			(stroke
				(width 0.1)
				(type default)
			)
			(layer "F.Fab")
		)
		(pad "1" smd circle
			(at -0.40005 0 270)
			(size 0 0)
			(layers "F.Cu" "F.Mask" "F.Paste")
			(net "P3V3_NIC0")
		)
		(pad "2" smd circle
			(at 0.40005 0 270)
			(size 0 0)
			(layers "F.Cu" "F.Mask" "F.Paste")
			(net "GND")
		)
	)
	(footprint ""
		(layer "F.Cu")
		(at 253.455678 -152.71115 90)
		(property "Reference" "R729"
			(at 0 0 90)
			(layer "F.SilkS")
			(hide yes)
			(effects
				(font
					(size 1.27 1.27)
				)
			)
		)
		(property "Value" ""
			(at 0 0 90)
			(layer "F.Fab")
			(effects
				(font
					(size 1.27 1.27)
				)
			)
		)
		(duplicate_pad_numbers_are_jumpers no)
		(fp_line
			(start 0.7874 -0.4064)
			(end 0.7874 0.4064)
			(stroke
				(width 0.1524)
				(type default)
			)
			(layer "F.SilkS")
		)
		(fp_line
			(start -0.7874 -0.4064)
			(end 0.7874 -0.4064)
			(stroke
				(width 0.1524)
				(type default)
			)
			(layer "F.SilkS")
		)
		(fp_line
			(start 0.7874 0.4064)
			(end -0.7874 0.4064)
			(stroke
				(width 0.1524)
				(type default)
			)
			(layer "F.SilkS")
		)
		(fp_line
			(start -0.7874 0.4064)
			(end -0.7874 -0.4064)
			(stroke
				(width 0.1524)
				(type default)
			)
			(layer "F.SilkS")
		)
		(fp_line
			(start -0.12065 -0.305054)
			(end -0.12065 -0.2794)
			(stroke
				(width 0.1)
				(type default)
			)
			(layer "F.Fab")
		)
		(fp_line
			(start -0.67945 -0.305054)
			(end -0.12065 -0.305054)
			(stroke
				(width 0.1)
				(type default)
			)
			(layer "F.Fab")
		)
		(fp_line
			(start 0.67945 -0.3048)
			(end 0.67945 0.3048)
			(stroke
				(width 0.1)
				(type default)
			)
			(layer "F.Fab")
		)
		(fp_line
			(start 0.12065 -0.3048)
			(end 0.67945 -0.3048)
			(stroke
				(width 0.1)
				(type default)
			)
			(layer "F.Fab")
		)
		(fp_line
			(start 0.12065 -0.2794)
			(end 0.12065 -0.3048)
			(stroke
				(width 0.1)
				(type default)
			)
			(layer "F.Fab")
		)
		(fp_line
			(start -0.12065 -0.2794)
			(end 0.12065 -0.2794)
			(stroke
				(width 0.1)
				(type default)
			)
			(layer "F.Fab")
		)
		(fp_line
			(start 0.120396 0.2794)
			(end -0.12065 0.2794)
			(stroke
				(width 0.1)
				(type default)
			)
			(layer "F.Fab")
		)
		(fp_line
			(start -0.12065 0.2794)
			(end -0.12065 0.3048)
			(stroke
				(width 0.1)
				(type default)
			)
			(layer "F.Fab")
		)
		(fp_line
			(start 0.67945 0.3048)
			(end 0.120396 0.3048)
			(stroke
				(width 0.1)
				(type default)
			)
			(layer "F.Fab")
		)
		(fp_line
			(start 0.120396 0.3048)
			(end 0.120396 0.2794)
			(stroke
				(width 0.1)
				(type default)
			)
			(layer "F.Fab")
		)
		(fp_line
			(start -0.12065 0.3048)
			(end -0.67945 0.3048)
			(stroke
				(width 0.1)
				(type default)
			)
			(layer "F.Fab")
		)
		(fp_line
			(start -0.67945 0.3048)
			(end -0.67945 -0.305054)
			(stroke
				(width 0.1)
				(type default)
			)
			(layer "F.Fab")
		)
		(pad "1" smd circle
			(at -0.40005 0 90)
			(size 0 0)
			(layers "F.Cu" "F.Mask" "F.Paste")
			(net "NIC4_ADC_A1")
		)
		(pad "2" smd circle
			(at 0.40005 0 90)
			(size 0 0)
			(layers "F.Cu" "F.Mask" "F.Paste")
			(net "GND")
		)
	)
	(footprint ""
		(layer "F.Cu")
		(at 211.400136 -181.613556 -90)
		(property "Reference" "C3626"
			(at 0 0 270)
			(layer "F.SilkS")
			(hide yes)
			(effects
				(font
					(size 1.27 1.27)
				)
			)
		)
		(property "Value" ""
			(at 0 0 270)
			(layer "F.Fab")
			(effects
				(font
					(size 1.27 1.27)
				)
			)
		)
		(duplicate_pad_numbers_are_jumpers no)
		(fp_line
			(start -0.7874 0.4064)
			(end -0.7874 -0.4064)
			(stroke
				(width 0.1524)
				(type default)
			)
			(layer "F.SilkS")
		)
		(fp_line
			(start 0.7874 0.4064)
			(end -0.7874 0.4064)
			(stroke
				(width 0.1524)
				(type default)
			)
			(layer "F.SilkS")
		)
		(fp_line
			(start -0.7874 -0.4064)
			(end 0.7874 -0.4064)
			(stroke
				(width 0.1524)
				(type default)
			)
			(layer "F.SilkS")
		)
		(fp_line
			(start 0.7874 -0.4064)
			(end 0.7874 0.4064)
			(stroke
				(width 0.1524)
				(type default)
			)
			(layer "F.SilkS")
		)
		(fp_line
			(start -0.67945 0.3048)
			(end -0.67945 -0.305054)
			(stroke
				(width 0.1)
				(type default)
			)
			(layer "F.Fab")
		)
		(fp_line
			(start -0.12065 0.3048)
			(end -0.67945 0.3048)
			(stroke
				(width 0.1)
				(type default)
			)
			(layer "F.Fab")
		)
		(fp_line
			(start 0.120396 0.3048)
			(end 0.120396 0.2794)
			(stroke
				(width 0.1)
				(type default)
			)
			(layer "F.Fab")
		)
		(fp_line
			(start 0.67945 0.3048)
			(end 0.120396 0.3048)
			(stroke
				(width 0.1)
				(type default)
			)
			(layer "F.Fab")
		)
		(fp_line
			(start -0.12065 0.2794)
			(end -0.12065 0.3048)
			(stroke
				(width 0.1)
				(type default)
			)
			(layer "F.Fab")
		)
		(fp_line
			(start 0.120396 0.2794)
			(end -0.12065 0.2794)
			(stroke
				(width 0.1)
				(type default)
			)
			(layer "F.Fab")
		)
		(fp_line
			(start -0.12065 -0.2794)
			(end 0.12065 -0.2794)
			(stroke
				(width 0.1)
				(type default)
			)
			(layer "F.Fab")
		)
		(fp_line
			(start 0.12065 -0.2794)
			(end 0.12065 -0.3048)
			(stroke
				(width 0.1)
				(type default)
			)
			(layer "F.Fab")
		)
		(fp_line
			(start 0.12065 -0.3048)
			(end 0.67945 -0.3048)
			(stroke
				(width 0.1)
				(type default)
			)
			(layer "F.Fab")
		)
		(fp_line
			(start 0.67945 -0.3048)
			(end 0.67945 0.3048)
			(stroke
				(width 0.1)
				(type default)
			)
			(layer "F.Fab")
		)
		(fp_line
			(start -0.67945 -0.305054)
			(end -0.12065 -0.305054)
			(stroke
				(width 0.1)
				(type default)
			)
			(layer "F.Fab")
		)
		(fp_line
			(start -0.12065 -0.305054)
			(end -0.12065 -0.2794)
			(stroke
				(width 0.1)
				(type default)
			)
			(layer "F.Fab")
		)
		(pad "1" smd circle
			(at -0.40005 0 270)
			(size 0 0)
			(layers "F.Cu" "F.Mask" "F.Paste")
			(net "P3V3_AUX")
		)
		(pad "2" smd circle
			(at 0.40005 0 270)
			(size 0 0)
			(layers "F.Cu" "F.Mask" "F.Paste")
			(net "GND")
		)
	)
)
